# S9S_MB_2U (Grand Teton) — schematic netlist excerpt (pin names and nets, part order shuffled) for the footprints in the layout excerpt that follows; sources: Cadence DE-HDL packaged netlist, KiCad conversion of 03242023_DA0F0TMBIJ0_F0T_Motherboard_J_brd_V01_OCP.brd

PC588  Q_CAPP  270UF 16V 20% OSCON  pkg THLF  page 285 : A = SW_P12V_PVCCIN_CPU1_FLT ; B = GND
R4689  Q_RES  33.2 1% EMPTY  pkg 0402LF  page 251 : A = SMB_LM75_0_3V3AUX_SCL ; B = SMB_HSC_TYPE_ADC_SCL
C997  Q_CAP  10UF 6.3V 20% X6S  pkg C0402  page 74 : A = PVCCIN_CPU0 ; B = GND

(kicad_pcb
	(version 20260206)
	(generator "pcbnew")
	(generator_version "10.0")
	(general
		(thickness 1.6)
		(legacy_teardrops no)
	)
	(paper "A4")
	(title_block
		(title "03242023_DA0F0TMBIJ0_F0T_Motherboard_J_brd_V01_OCP.brd")
		(comment 1 "Grand Teton / footprints 467-469 of 6105")
	)
	(layers
		(0 "F.Cu" signal "TOP")
		(4 "In1.Cu" signal "GND")
		(6 "In2.Cu" signal "IN1")
		(8 "In3.Cu" signal "GND1")
		(10 "In4.Cu" signal "IN2")
		(12 "In5.Cu" signal "GND2")
		(14 "In6.Cu" signal "IN3")
		(16 "In7.Cu" signal "GND3")
		(18 "In8.Cu" signal "VCC")
		(20 "In9.Cu" signal "VCC1")
		(22 "In10.Cu" signal "GND4")
		(24 "In11.Cu" signal "IN4")
		(26 "In12.Cu" signal "GND5")
		(28 "In13.Cu" signal "IN5")
		(30 "In14.Cu" signal "GND6")
		(32 "In15.Cu" signal "IN6")
		(34 "In16.Cu" signal "GND7")
		(2 "B.Cu" signal "BOTTOM")
		(9 "F.Adhes" user "F.Adhesive")
		(11 "B.Adhes" user "B.Adhesive")
		(13 "F.Paste" user "Package Geometry/Pastemask Top")
		(15 "B.Paste" user "Package Geometry/Pastemask Bottom")
		(5 "F.SilkS" user "Ref Des/Silkscreen Top")
		(7 "B.SilkS" user "Ref Des/Silkscreen Bottom")
		(1 "F.Mask" user "Board Geometry/Soldermask Top")
		(3 "B.Mask" user "Board Geometry/Soldermask Bottom")
		(17 "Dwgs.User" user "User.Drawings")
		(19 "Cmts.User" user "User.Comments")
		(21 "Eco1.User" user "User.Eco1")
		(23 "Eco2.User" user "User.Eco2")
		(25 "Edge.Cuts" user "Board Geometry/Outline")
		(27 "Margin" user)
		(31 "F.CrtYd" user "Package Geometry/Place Bound Top")
		(29 "B.CrtYd" user "Package Geometry/Place Bound Bottom")
		(35 "F.Fab" user "Ref Des/Assembly Top")
		(33 "B.Fab" user "Ref Des/Assembly Bottom")
	)
	(footprint ""
		(layer "F.Cu")
		(at 364.50143 -245.634002 -90)
		(property "Reference" "C997"
			(at 0 0 270)
			(layer "F.SilkS")
			(hide yes)
			(effects
				(font
					(size 1.27 1.27)
				)
			)
		)
		(property "Value" ""
			(at 0 0 270)
			(layer "F.Fab")
			(effects
				(font
					(size 1.27 1.27)
				)
			)
		)
		(duplicate_pad_numbers_are_jumpers no)
		(fp_line
			(start -0.7874 0.4064)
			(end -0.7874 -0.4064)
			(stroke
				(width 0.1524)
				(type default)
			)
			(layer "F.SilkS")
		)
		(fp_line
			(start 0.7874 0.4064)
			(end -0.7874 0.4064)
			(stroke
				(width 0.1524)
				(type default)
			)
			(layer "F.SilkS")
		)
		(fp_line
			(start -0.7874 -0.4064)
			(end 0.7874 -0.4064)
			(stroke
				(width 0.1524)
				(type default)
			)
			(layer "F.SilkS")
		)
		(fp_line
			(start 0.7874 -0.4064)
			(end 0.7874 0.4064)
			(stroke
				(width 0.1524)
				(type default)
			)
			(layer "F.SilkS")
		)
		(fp_line
			(start -0.67945 0.3048)
			(end -0.67945 -0.305054)
			(stroke
				(width 0.1)
				(type default)
			)
			(layer "F.Fab")
		)
		(fp_line
			(start -0.12065 0.3048)
			(end -0.67945 0.3048)
			(stroke
				(width 0.1)
				(type default)
			)
			(layer "F.Fab")
		)
		(fp_line
			(start 0.120396 0.3048)
			(end 0.120396 0.2794)
			(stroke
				(width 0.1)
				(type default)
			)
			(layer "F.Fab")
		)
		(fp_line
			(start 0.67945 0.3048)
			(end 0.120396 0.3048)
			(stroke
				(width 0.1)
				(type default)
			)
			(layer "F.Fab")
		)
		(fp_line
			(start -0.12065 0.2794)
			(end -0.12065 0.3048)
			(stroke
				(width 0.1)
				(type default)
			)
			(layer "F.Fab")
		)
		(fp_line
			(start 0.120396 0.2794)
			(end -0.12065 0.2794)
			(stroke
				(width 0.1)
				(type default)
			)
			(layer "F.Fab")
		)
		(fp_line
			(start -0.12065 -0.2794)
			(end 0.12065 -0.2794)
			(stroke
				(width 0.1)
				(type default)
			)
			(layer "F.Fab")
		)
		(fp_line
			(start 0.12065 -0.2794)
			(end 0.12065 -0.3048)
			(stroke
				(width 0.1)
				(type default)
			)
			(layer "F.Fab")
		)
		(fp_line
			(start 0.12065 -0.3048)
			(end 0.67945 -0.3048)
			(stroke
				(width 0.1)
				(type default)
			)
			(layer "F.Fab")
		)
		(fp_line
			(start 0.67945 -0.3048)
			(end 0.67945 0.3048)
			(stroke
				(width 0.1)
				(type default)
			)
			(layer "F.Fab")
		)
		(fp_line
			(start -0.67945 -0.305054)
			(end -0.12065 -0.305054)
			(stroke
				(width 0.1)
				(type default)
			)
			(layer "F.Fab")
		)
		(fp_line
			(start -0.12065 -0.305054)
			(end -0.12065 -0.2794)
			(stroke
				(width 0.1)
				(type default)
			)
			(layer "F.Fab")
		)
		(pad "1" smd circle
			(at -0.40005 0 270)
			(size 0 0)
			(layers "F.Cu" "F.Mask" "F.Paste")
			(net "PVCCIN_CPU0")
		)
		(pad "2" smd circle
			(at 0.40005 0 270)
			(size 0 0)
			(layers "F.Cu" "F.Mask" "F.Paste")
			(net "GND")
		)
	)
	(footprint ""
		(layer "F.Cu")
		(at 299.865034 -409.69184)
		(property "Reference" "R4689"
			(at 0 0 0)
			(layer "F.SilkS")
			(hide yes)
			(effects
				(font
					(size 1.27 1.27)
				)
			)
		)
		(property "Value" ""
			(at 0 0 0)
			(layer "F.Fab")
			(effects
				(font
					(size 1.27 1.27)
				)
			)
		)
		(duplicate_pad_numbers_are_jumpers no)
		(fp_line
			(start -0.7874 -0.4064)
			(end 0.7874 -0.4064)
			(stroke
				(width 0.1524)
				(type default)
			)
			(layer "F.SilkS")
		)
		(fp_line
			(start -0.7874 0.4064)
			(end -0.7874 -0.4064)
			(stroke
				(width 0.1524)
				(type default)
			)
			(layer "F.SilkS")
		)
		(fp_line
			(start 0.7874 -0.4064)
			(end 0.7874 0.4064)
			(stroke
				(width 0.1524)
				(type default)
			)
			(layer "F.SilkS")
		)
		(fp_line
			(start 0.7874 0.4064)
			(end -0.7874 0.4064)
			(stroke
				(width 0.1524)
				(type default)
			)
			(layer "F.SilkS")
		)
		(fp_line
			(start -0.67945 -0.305054)
			(end -0.12065 -0.305054)
			(stroke
				(width 0.1)
				(type default)
			)
			(layer "F.Fab")
		)
		(fp_line
			(start -0.67945 0.3048)
			(end -0.67945 -0.305054)
			(stroke
				(width 0.1)
				(type default)
			)
			(layer "F.Fab")
		)
		(fp_line
			(start -0.12065 -0.305054)
			(end -0.12065 -0.2794)
			(stroke
				(width 0.1)
				(type default)
			)
			(layer "F.Fab")
		)
		(fp_line
			(start -0.12065 -0.2794)
			(end 0.12065 -0.2794)
			(stroke
				(width 0.1)
				(type default)
			)
			(layer "F.Fab")
		)
		(fp_line
			(start -0.12065 0.2794)
			(end -0.12065 0.3048)
			(stroke
				(width 0.1)
				(type default)
			)
			(layer "F.Fab")
		)
		(fp_line
			(start -0.12065 0.3048)
			(end -0.67945 0.3048)
			(stroke
				(width 0.1)
				(type default)
			)
			(layer "F.Fab")
		)
		(fp_line
			(start 0.120396 0.2794)
			(end -0.12065 0.2794)
			(stroke
				(width 0.1)
				(type default)
			)
			(layer "F.Fab")
		)
		(fp_line
			(start 0.120396 0.3048)
			(end 0.120396 0.2794)
			(stroke
				(width 0.1)
				(type default)
			)
			(layer "F.Fab")
		)
		(fp_line
			(start 0.12065 -0.3048)
			(end 0.67945 -0.3048)
			(stroke
				(width 0.1)
				(type default)
			)
			(layer "F.Fab")
		)
		(fp_line
			(start 0.12065 -0.2794)
			(end 0.12065 -0.3048)
			(stroke
				(width 0.1)
				(type default)
			)
			(layer "F.Fab")
		)
		(fp_line
			(start 0.67945 -0.3048)
			(end 0.67945 0.3048)
			(stroke
				(width 0.1)
				(type default)
			)
			(layer "F.Fab")
		)
		(fp_line
			(start 0.67945 0.3048)
			(end 0.120396 0.3048)
			(stroke
				(width 0.1)
				(type default)
			)
			(layer "F.Fab")
		)
		(pad "1" smd circle
			(at -0.40005 0)
			(size 0 0)
			(layers "F.Cu" "F.Mask" "F.Paste")
			(net "SMB_LM75_0_3V3AUX_SCL")
		)
		(pad "2" smd circle
			(at 0.40005 0)
			(size 0 0)
			(layers "F.Cu" "F.Mask" "F.Paste")
			(net "SMB_HSC_TYPE_ADC_SCL")
		)
	)
	(footprint ""
		(layer "F.Cu")
		(at 104.89946 -344.029284 90)
		(property "Reference" "PC588"
			(at 0 0 90)
			(layer "F.SilkS")
			(hide yes)
			(effects
				(font
					(size 1.27 1.27)
				)
			)
		)
		(property "Value" ""
			(at 0 0 90)
			(layer "F.Fab")
			(effects
				(font
					(size 1.27 1.27)
				)
			)
		)
		(duplicate_pad_numbers_are_jumpers no)
		(fp_line
			(start -3.400044 1.249934)
			(end 3.400044 1.249934)
			(stroke
				(width 0.1524)
				(type default)
			)
			(layer "F.SilkS")
		)
		(fp_circle
			(center 0 1.249934)
			(end 0 4.649978)
			(stroke
				(width 0.1524)
				(type default)
			)
			(fill no)
			(layer "F.SilkS")
		)
		(fp_poly
			(pts
				(arc
					(start -3.400044 1.249934)
					(mid 0 4.649978)
					(end 3.400044 1.249934)
				)
			)
			(stroke
				(width 0)
				(type default)
			)
			(fill yes)
			(layer "F.SilkS")
		)
		(fp_circle
			(center 0 1.249934)
			(end 0 4.649978)
			(stroke
				(width 0.1)
				(type default)
			)
			(fill no)
			(layer "F.Fab")
		)
		(pad "1" thru_hole rect
			(at 0 0 90)
			(size 1.524 1.524)
			(drill 1.016)
			(layers "*.Cu" "*.Mask")
			(remove_unused_layers no)
			(net "SW_P12V_PVCCIN_CPU1_FLT")
			(clearance 0)
			(padstack
				(mode front_inner_back)
				(layer "Inner"
					(shape circle)
					(size 1.524 1.524)
					(clearance 0)
				)
				(layer "B.Cu"
					(shape rect)
					(size 1.524 1.524)
					(clearance 0)
				)
			)
		)
		(pad "2" thru_hole circle
			(at 0 2.500122 90)
			(size 1.524 1.524)
			(drill 1.016)
			(layers "*.Cu" "*.Mask")
			(remove_unused_layers no)
			(net "GND")
			(clearance 0)
		)
	)
)
